# TIMECARD (Time Appliance Project (Time Card)) — schematic netlist excerpt (pin names and nets, part order shuffled) for the footprints in the layout excerpt that follows; sources: Cadence DE-HDL packaged netlist, KiCad conversion of R4006-B0001-02_R01.brd

R470  RESISTOR  33OHM 1%  pkg SMC_0402R_H016  page 24 : \1\ = R_FT4232_TMS ; \2\ = FT4232_TMS_SPICS_N
R466  RESISTOR  100KOHM 1%  pkg SMC_0402R_H016  page 24 : \1\ = R_FT4232_TDO ; \2\ = XP3R3V_FT4232

(kicad_pcb
	(version 20260206)
	(generator "pcbnew")
	(generator_version "10.0")
	(general
		(thickness 1.6)
		(legacy_teardrops no)
	)
	(paper "A4")
	(title_block
		(title "timecard-production-celestica-r4006 — R4006-B0001-02_R01.brd")
		(comment 1 "Time Appliance Project (Time Card) / footprints 722-723 of 1113")
	)
	(layers
		(0 "F.Cu" signal "TOP")
		(4 "In1.Cu" signal "L02_GND1")
		(6 "In2.Cu" signal "L03_SIG1")
		(8 "In3.Cu" signal "L04_GND2")
		(10 "In4.Cu" signal "L05_VCC1")
		(12 "In5.Cu" signal "L06_VCC2")
		(14 "In6.Cu" signal "L07_GND3")
		(16 "In7.Cu" signal "L08_SIG2")
		(18 "In8.Cu" signal "L09_GND4")
		(2 "B.Cu" signal "BOTTOM")
		(9 "F.Adhes" user "F.Adhesive")
		(11 "B.Adhes" user "B.Adhesive")
		(13 "F.Paste" user "Package Geometry/Pastemask Top")
		(15 "B.Paste" user "Package Geometry/Pastemask Bottom")
		(5 "F.SilkS" user "Ref Des/Silkscreen Top")
		(7 "B.SilkS" user "Ref Des/Silkscreen Bottom")
		(1 "F.Mask" user "Board Geometry/Soldermask Top")
		(3 "B.Mask" user "Board Geometry/Soldermask Bottom")
		(17 "Dwgs.User" user "User.Drawings")
		(19 "Cmts.User" user "User.Comments")
		(21 "Eco1.User" user "User.Eco1")
		(23 "Eco2.User" user "User.Eco2")
		(25 "Edge.Cuts" user "Board Geometry/Outline")
		(27 "Margin" user)
		(31 "F.CrtYd" user "Package Geometry/Place Bound Top")
		(29 "B.CrtYd" user "Package Geometry/Place Bound Bottom")
		(35 "F.Fab" user "Ref Des/Assembly Top")
		(33 "B.Fab" user "Ref Des/Assembly Bottom")
	)
	(footprint ""
		(layer "B.Cu")
		(at 22.606 -86.614 180)
		(property "Reference" "R470"
			(at -1.016 -3.34137 0)
			(unlocked yes)
			(layer "B.SilkS")
			(effects
				(font
					(size 0.7874 0.5842)
					(thickness 0.1524)
				)
				(justify mirror)
			)
		)
		(property "Value" "VAL*"
			(at -0.02032 2.13233 180)
			(unlocked yes)
			(layer "B.Fab")
			(hide yes)
			(effects
				(font
					(size 0.7874 0.5842)
					(thickness 0.1524)
				)
				(justify mirror)
			)
		)
		(property "Tolerance" "TOL*"
			(at -0.044704 3.05435 180)
			(unlocked yes)
			(layer "Cmts.User")
			(hide yes)
			(effects
				(font
					(size 0.7874 0.5842)
					(thickness 0.1524)
				)
				(justify mirror)
			)
		)
		(property "User Part Number" "PARTNUM*"
			(at -0.02032 4.024884 180)
			(unlocked yes)
			(layer "Cmts.User")
			(hide yes)
			(effects
				(font
					(size 0.7874 0.5842)
					(thickness 0.1524)
				)
				(justify mirror)
			)
		)
		(property "Device Type" "RESISTOR-G155-133R0-01,33OHM,1%"
			(at -0.008382 1.210564 180)
			(unlocked yes)
			(layer "B.Fab")
			(hide yes)
			(effects
				(font
					(size 0.7874 0.5842)
					(thickness 0.1524)
				)
				(justify mirror)
			)
		)
		(duplicate_pad_numbers_are_jumpers no)
		(fp_line
			(start 1.143 0.5588)
			(end -1.143 0.5588)
			(stroke
				(width 0.1)
				(type default)
			)
			(layer "B.SilkS")
		)
		(fp_line
			(start 1.143 -0.5588)
			(end 1.143 0.5588)
			(stroke
				(width 0.1)
				(type default)
			)
			(layer "B.SilkS")
		)
		(fp_line
			(start -1.143 0.5588)
			(end -1.143 -0.5588)
			(stroke
				(width 0.1)
				(type default)
			)
			(layer "B.SilkS")
		)
		(fp_line
			(start -1.143 -0.5588)
			(end 1.143 -0.5588)
			(stroke
				(width 0.1)
				(type default)
			)
			(layer "B.SilkS")
		)
		(fp_poly
			(pts
				(xy 1.143 0.5588) (xy -1.143 0.5588) (xy -1.143 -0.5588) (xy 1.143 -0.5588)
			)
			(stroke
				(width 0)
				(type default)
			)
			(fill no)
			(layer "B.CrtYd")
		)
		(fp_line
			(start 0.508 0.3048)
			(end -0.508 0.3048)
			(stroke
				(width 0.1)
				(type default)
			)
			(layer "B.Fab")
		)
		(fp_line
			(start 0.508 -0.3048)
			(end 0.508 0.3048)
			(stroke
				(width 0.1)
				(type default)
			)
			(layer "B.Fab")
		)
		(fp_line
			(start -0.508 0.3048)
			(end -0.508 -0.3048)
			(stroke
				(width 0.1)
				(type default)
			)
			(layer "B.Fab")
		)
		(fp_line
			(start -0.508 -0.3048)
			(end 0.508 -0.3048)
			(stroke
				(width 0.1)
				(type default)
			)
			(layer "B.Fab")
		)
		(pad "1" smd rect
			(at 0.5334 0)
			(size 0.7112 0.6096)
			(layers "B.Cu" "B.Mask" "B.Paste")
			(net "R_FT4232_TMS")
		)
		(pad "2" smd rect
			(at -0.5334 0)
			(size 0.7112 0.6096)
			(layers "B.Cu" "B.Mask" "B.Paste")
			(net "FT4232_TMS_SPICS_N")
		)
		(zone
			(layer "B.Cu")
			(hatch none 0.5)
			(connect_pads
				(clearance 0)
			)
			(min_thickness 0.25)
			(keepout
				(tracks not_allowed)
				(vias allowed)
				(pads allowed)
				(copperpour not_allowed)
				(footprints allowed)
			)
			(placement
				(enabled no)
				(sheetname "")
			)
			(fill
				(thermal_gap 0.5)
				(thermal_bridge_width 0.5)
				(island_removal_mode 0)
			)
			(polygon
				(pts
					(xy 22.5298 -86.9188) (xy 22.5298 -86.3092) (xy 22.6822 -86.3092) (xy 22.6822 -86.9188)
				)
			)
		)
		(zone
			(layer "B.Cu")
			(hatch none 0.5)
			(connect_pads
				(clearance 0)
			)
			(min_thickness 0.25)
			(keepout
				(tracks allowed)
				(vias not_allowed)
				(pads allowed)
				(copperpour not_allowed)
				(footprints allowed)
			)
			(placement
				(enabled no)
				(sheetname "")
			)
			(fill
				(thermal_gap 0.5)
				(thermal_bridge_width 0.5)
				(island_removal_mode 0)
			)
			(polygon
				(pts
					(xy 22.5298 -86.9188) (xy 22.5298 -86.3092) (xy 22.6822 -86.3092) (xy 22.6822 -86.9188)
				)
			)
		)
	)
	(footprint ""
		(layer "B.Cu")
		(at 22.606 -87.757 180)
		(property "Reference" "R466"
			(at -1.016 -3.46837 0)
			(unlocked yes)
			(layer "B.SilkS")
			(effects
				(font
					(size 0.7874 0.5842)
					(thickness 0.1524)
				)
				(justify mirror)
			)
		)
		(property "Value" "VAL*"
			(at -0.02032 2.13233 180)
			(unlocked yes)
			(layer "B.Fab")
			(hide yes)
			(effects
				(font
					(size 0.7874 0.5842)
					(thickness 0.1524)
				)
				(justify mirror)
			)
		)
		(property "Tolerance" "TOL*"
			(at -0.044704 3.05435 180)
			(unlocked yes)
			(layer "Cmts.User")
			(hide yes)
			(effects
				(font
					(size 0.7874 0.5842)
					(thickness 0.1524)
				)
				(justify mirror)
			)
		)
		(property "User Part Number" "PARTNUM*"
			(at -0.02032 4.024884 180)
			(unlocked yes)
			(layer "Cmts.User")
			(hide yes)
			(effects
				(font
					(size 0.7874 0.5842)
					(thickness 0.1524)
				)
				(justify mirror)
			)
		)
		(property "Device Type" "RESISTOR-G155-11003-01,100KOHMA"
			(at -0.008382 1.210564 180)
			(unlocked yes)
			(layer "B.Fab")
			(hide yes)
			(effects
				(font
					(size 0.7874 0.5842)
					(thickness 0.1524)
				)
				(justify mirror)
			)
		)
		(duplicate_pad_numbers_are_jumpers no)
		(fp_line
			(start 1.143 0.5588)
			(end -1.143 0.5588)
			(stroke
				(width 0.1)
				(type default)
			)
			(layer "B.SilkS")
		)
		(fp_line
			(start 1.143 -0.5588)
			(end 1.143 0.5588)
			(stroke
				(width 0.1)
				(type default)
			)
			(layer "B.SilkS")
		)
		(fp_line
			(start -1.143 0.5588)
			(end -1.143 -0.5588)
			(stroke
				(width 0.1)
				(type default)
			)
			(layer "B.SilkS")
		)
		(fp_line
			(start -1.143 -0.5588)
			(end 1.143 -0.5588)
			(stroke
				(width 0.1)
				(type default)
			)
			(layer "B.SilkS")
		)
		(fp_poly
			(pts
				(xy 1.143 0.5588) (xy -1.143 0.5588) (xy -1.143 -0.5588) (xy 1.143 -0.5588)
			)
			(stroke
				(width 0)
				(type default)
			)
			(fill no)
			(layer "B.CrtYd")
		)
		(fp_line
			(start 0.508 0.3048)
			(end -0.508 0.3048)
			(stroke
				(width 0.1)
				(type default)
			)
			(layer "B.Fab")
		)
		(fp_line
			(start 0.508 -0.3048)
			(end 0.508 0.3048)
			(stroke
				(width 0.1)
				(type default)
			)
			(layer "B.Fab")
		)
		(fp_line
			(start -0.508 0.3048)
			(end -0.508 -0.3048)
			(stroke
				(width 0.1)
				(type default)
			)
			(layer "B.Fab")
		)
		(fp_line
			(start -0.508 -0.3048)
			(end 0.508 -0.3048)
			(stroke
				(width 0.1)
				(type default)
			)
			(layer "B.Fab")
		)
		(pad "1" smd rect
			(at 0.5334 0)
			(size 0.7112 0.6096)
			(layers "B.Cu" "B.Mask" "B.Paste")
			(net "R_FT4232_TDO")
		)
		(pad "2" smd rect
			(at -0.5334 0)
			(size 0.7112 0.6096)
			(layers "B.Cu" "B.Mask" "B.Paste")
			(net "XP3R3V_FT4232")
		)
		(zone
			(layer "B.Cu")
			(hatch none 0.5)
			(connect_pads
				(clearance 0)
			)
			(min_thickness 0.25)
			(keepout
				(tracks allowed)
				(vias not_allowed)
				(pads allowed)
				(copperpour not_allowed)
				(footprints allowed)
			)
			(placement
				(enabled no)
				(sheetname "")
			)
			(fill
				(thermal_gap 0.5)
				(thermal_bridge_width 0.5)
				(island_removal_mode 0)
			)
			(polygon
				(pts
					(xy 22.5298 -88.0618) (xy 22.5298 -87.4522) (xy 22.6822 -87.4522) (xy 22.6822 -88.0618)
				)
			)
		)
		(zone
			(layer "B.Cu")
			(hatch none 0.5)
			(connect_pads
				(clearance 0)
			)
			(min_thickness 0.25)
			(keepout
				(tracks not_allowed)
				(vias allowed)
				(pads allowed)
				(copperpour not_allowed)
				(footprints allowed)
			)
			(placement
				(enabled no)
				(sheetname "")
			)
			(fill
				(thermal_gap 0.5)
				(thermal_bridge_width 0.5)
				(island_removal_mode 0)
			)
			(polygon
				(pts
					(xy 22.5298 -88.0618) (xy 22.5298 -87.4522) (xy 22.6822 -87.4522) (xy 22.6822 -88.0618)
				)
			)
		)
	)
)
